# TIMECARD (Time Appliance Project (Time Card)) — schematic netlist excerpt (pin names and nets, part order shuffled) for the footprints in the layout excerpt that follows; sources: Cadence DE-HDL packaged netlist, KiCad conversion of R4006-B0001-02_R01.brd

R437  RESISTOR  15KOHM 1%  pkg SMC_0402R_H016  page 11 : \1\ = SG ; \2\ = MAC_USB_DM
R494  RESISTOR  0OHM -  pkg SMC_0402R_H016  page 23 : \1\ = UNNAMED_12_CAPACITOR_I328_2 ; \2\ = UNNAMED_12_74HCT2G125DPTSSOP8_6

(kicad_pcb
	(version 20260206)
	(generator "pcbnew")
	(generator_version "10.0")
	(general
		(thickness 1.6)
		(legacy_teardrops no)
	)
	(paper "A4")
	(title_block
		(title "timecard-production-celestica-r4006 — R4006-B0001-02_R01.brd")
		(comment 1 "Time Appliance Project (Time Card) / footprints 829-830 of 1113")
	)
	(layers
		(0 "F.Cu" signal "TOP")
		(4 "In1.Cu" signal "L02_GND1")
		(6 "In2.Cu" signal "L03_SIG1")
		(8 "In3.Cu" signal "L04_GND2")
		(10 "In4.Cu" signal "L05_VCC1")
		(12 "In5.Cu" signal "L06_VCC2")
		(14 "In6.Cu" signal "L07_GND3")
		(16 "In7.Cu" signal "L08_SIG2")
		(18 "In8.Cu" signal "L09_GND4")
		(2 "B.Cu" signal "BOTTOM")
		(9 "F.Adhes" user "F.Adhesive")
		(11 "B.Adhes" user "B.Adhesive")
		(13 "F.Paste" user "Package Geometry/Pastemask Top")
		(15 "B.Paste" user "Package Geometry/Pastemask Bottom")
		(5 "F.SilkS" user "Ref Des/Silkscreen Top")
		(7 "B.SilkS" user "Ref Des/Silkscreen Bottom")
		(1 "F.Mask" user "Board Geometry/Soldermask Top")
		(3 "B.Mask" user "Board Geometry/Soldermask Bottom")
		(17 "Dwgs.User" user "User.Drawings")
		(19 "Cmts.User" user "User.Comments")
		(21 "Eco1.User" user "User.Eco1")
		(23 "Eco2.User" user "User.Eco2")
		(25 "Edge.Cuts" user "Board Geometry/Outline")
		(27 "Margin" user)
		(31 "F.CrtYd" user "Package Geometry/Place Bound Top")
		(29 "B.CrtYd" user "Package Geometry/Place Bound Bottom")
		(35 "F.Fab" user "Ref Des/Assembly Top")
		(33 "B.Fab" user "Ref Des/Assembly Bottom")
	)
	(footprint ""
		(layer "B.Cu")
		(at 113.847118 -46.322996 -90)
		(property "Reference" "R437"
			(at 1.999996 43.139868 270)
			(unlocked yes)
			(layer "B.SilkS")
			(effects
				(font
					(size 0.635 0.4064)
					(thickness 0.1524)
				)
				(justify mirror)
			)
		)
		(property "Value" "VAL*"
			(at 0 3.718306 270)
			(unlocked yes)
			(layer "B.Fab")
			(hide yes)
			(effects
				(font
					(size 0.7874 0.5842)
					(thickness 0.127)
				)
				(justify mirror)
			)
		)
		(property "Tolerance" "TOL*"
			(at 0 4.861306 270)
			(unlocked yes)
			(layer "Cmts.User")
			(hide yes)
			(effects
				(font
					(size 0.7874 0.5842)
					(thickness 0.127)
				)
				(justify mirror)
			)
		)
		(property "User Part Number" "PARTNUM*"
			(at 0 2.575306 270)
			(unlocked yes)
			(layer "Cmts.User")
			(hide yes)
			(effects
				(font
					(size 0.7874 0.5842)
					(thickness 0.127)
				)
				(justify mirror)
			)
		)
		(property "Device Type" "RESISTOR-G155-11502-01,15KOHM,A"
			(at 0 1.432306 270)
			(unlocked yes)
			(layer "B.Fab")
			(hide yes)
			(effects
				(font
					(size 0.7874 0.5842)
					(thickness 0.127)
				)
				(justify mirror)
			)
		)
		(duplicate_pad_numbers_are_jumpers no)
		(fp_line
			(start -0.970026 0.4699)
			(end 0.970026 0.4699)
			(stroke
				(width 0.1)
				(type default)
			)
			(layer "B.SilkS")
		)
		(fp_line
			(start 0.970026 0.4699)
			(end 0.970026 -0.4699)
			(stroke
				(width 0.1)
				(type default)
			)
			(layer "B.SilkS")
		)
		(fp_line
			(start -0.970026 -0.4699)
			(end -0.970026 0.4699)
			(stroke
				(width 0.1)
				(type default)
			)
			(layer "B.SilkS")
		)
		(fp_line
			(start 0.970026 -0.4699)
			(end -0.970026 -0.4699)
			(stroke
				(width 0.1)
				(type default)
			)
			(layer "B.SilkS")
		)
		(fp_poly
			(pts
				(xy 0.970026 0.4699) (xy -0.970026 0.4699) (xy -0.970026 -0.4699) (xy 0.970026 -0.4699)
			)
			(stroke
				(width 0)
				(type default)
			)
			(fill no)
			(layer "B.CrtYd")
		)
		(fp_line
			(start -0.508 0.3048)
			(end 0.508 0.3048)
			(stroke
				(width 0.1)
				(type default)
			)
			(layer "B.Fab")
		)
		(fp_line
			(start 0.508 0.3048)
			(end 0.508 -0.3048)
			(stroke
				(width 0.1)
				(type default)
			)
			(layer "B.Fab")
		)
		(fp_line
			(start -0.508 -0.3048)
			(end -0.508 0.3048)
			(stroke
				(width 0.1)
				(type default)
			)
			(layer "B.Fab")
		)
		(fp_line
			(start 0.508 -0.3048)
			(end -0.508 -0.3048)
			(stroke
				(width 0.1)
				(type default)
			)
			(layer "B.Fab")
		)
		(pad "1" smd circle
			(at 0.500126 0 90)
			(size 0.635 0.635)
			(layers "B.Cu" "B.Mask" "B.Paste")
			(net "SG")
		)
		(pad "2" smd circle
			(at -0.500126 0 90)
			(size 0.635 0.635)
			(layers "B.Cu" "B.Mask" "B.Paste")
			(net "MAC_USB_DM")
		)
	)
	(footprint ""
		(layer "B.Cu")
		(at 13.462 -66.167 90)
		(property "Reference" "R494"
			(at 0 1.23063 270)
			(unlocked yes)
			(layer "B.SilkS")
			(effects
				(font
					(size 0.7874 0.5842)
					(thickness 0.1524)
				)
				(justify mirror)
			)
		)
		(property "Value" "VAL*"
			(at -0.02032 2.13233 90)
			(unlocked yes)
			(layer "B.Fab")
			(hide yes)
			(effects
				(font
					(size 0.7874 0.5842)
					(thickness 0.1524)
				)
				(justify mirror)
			)
		)
		(property "Tolerance" "TOL*"
			(at -0.044704 3.05435 90)
			(unlocked yes)
			(layer "Cmts.User")
			(hide yes)
			(effects
				(font
					(size 0.7874 0.5842)
					(thickness 0.1524)
				)
				(justify mirror)
			)
		)
		(property "User Part Number" "PARTNUM*"
			(at -0.02032 4.024884 90)
			(unlocked yes)
			(layer "Cmts.User")
			(hide yes)
			(effects
				(font
					(size 0.7874 0.5842)
					(thickness 0.1524)
				)
				(justify mirror)
			)
		)
		(property "Device Type" "RESISTOR-G155-100R0-J0,0OHM,-"
			(at -0.008382 1.210564 90)
			(unlocked yes)
			(layer "B.Fab")
			(hide yes)
			(effects
				(font
					(size 0.7874 0.5842)
					(thickness 0.1524)
				)
				(justify mirror)
			)
		)
		(duplicate_pad_numbers_are_jumpers no)
		(fp_line
			(start 1.143 -0.5588)
			(end 1.143 0.5588)
			(stroke
				(width 0.1)
				(type default)
			)
			(layer "B.SilkS")
		)
		(fp_line
			(start -1.143 -0.5588)
			(end 1.143 -0.5588)
			(stroke
				(width 0.1)
				(type default)
			)
			(layer "B.SilkS")
		)
		(fp_line
			(start 1.143 0.5588)
			(end -1.143 0.5588)
			(stroke
				(width 0.1)
				(type default)
			)
			(layer "B.SilkS")
		)
		(fp_line
			(start -1.143 0.5588)
			(end -1.143 -0.5588)
			(stroke
				(width 0.1)
				(type default)
			)
			(layer "B.SilkS")
		)
		(fp_poly
			(pts
				(xy 1.143 0.5588) (xy -1.143 0.5588) (xy -1.143 -0.5588) (xy 1.143 -0.5588)
			)
			(stroke
				(width 0)
				(type default)
			)
			(fill no)
			(layer "B.CrtYd")
		)
		(fp_line
			(start 0.508 -0.3048)
			(end 0.508 0.3048)
			(stroke
				(width 0.1)
				(type default)
			)
			(layer "B.Fab")
		)
		(fp_line
			(start -0.508 -0.3048)
			(end 0.508 -0.3048)
			(stroke
				(width 0.1)
				(type default)
			)
			(layer "B.Fab")
		)
		(fp_line
			(start 0.508 0.3048)
			(end -0.508 0.3048)
			(stroke
				(width 0.1)
				(type default)
			)
			(layer "B.Fab")
		)
		(fp_line
			(start -0.508 0.3048)
			(end -0.508 -0.3048)
			(stroke
				(width 0.1)
				(type default)
			)
			(layer "B.Fab")
		)
		(pad "1" smd rect
			(at 0.5334 0 270)
			(size 0.7112 0.6096)
			(layers "B.Cu" "B.Mask" "B.Paste")
			(net "UNNAMED_12_CAPACITOR_I328_2")
		)
		(pad "2" smd rect
			(at -0.5334 0 270)
			(size 0.7112 0.6096)
			(layers "B.Cu" "B.Mask" "B.Paste")
			(net "UNNAMED_12_74HCT2G125DPTSSOP8_6")
		)
		(zone
			(layer "B.Cu")
			(hatch none 0.5)
			(connect_pads
				(clearance 0)
			)
			(min_thickness 0.25)
			(keepout
				(tracks allowed)
				(vias not_allowed)
				(pads allowed)
				(copperpour not_allowed)
				(footprints allowed)
			)
			(placement
				(enabled no)
				(sheetname "")
			)
			(fill
				(thermal_gap 0.5)
				(thermal_bridge_width 0.5)
				(island_removal_mode 0)
			)
			(polygon
				(pts
					(xy 13.7668 -66.2432) (xy 13.1572 -66.2432) (xy 13.1572 -66.0908) (xy 13.7668 -66.0908)
				)
			)
		)
		(zone
			(layer "B.Cu")
			(hatch none 0.5)
			(connect_pads
				(clearance 0)
			)
			(min_thickness 0.25)
			(keepout
				(tracks not_allowed)
				(vias allowed)
				(pads allowed)
				(copperpour not_allowed)
				(footprints allowed)
			)
			(placement
				(enabled no)
				(sheetname "")
			)
			(fill
				(thermal_gap 0.5)
				(thermal_bridge_width 0.5)
				(island_removal_mode 0)
			)
			(polygon
				(pts
					(xy 13.7668 -66.2432) (xy 13.1572 -66.2432) (xy 13.1572 -66.0908) (xy 13.7668 -66.0908)
				)
			)
		)
	)
)
